G04 ================== begin FILE IDENTIFICATION RECORD ==================*
G04 Layout Name:  D:/<user>/Wistron_project/16316-1/gbr-0621/16316-1.brd*
G04 Film Name:    P_OUTLINE*
G04 File Format:  Gerber RS274X*
G04 File Origin:  Cadence Allegro 16.5-S056*
G04 Origin Date:  Wed Jun 21 09:31:26 2017*
G04 *
G04 Layer:  BOARD GEOMETRY/PANEL_OUTLINE*
G04 *
G04 Offset:    (0.00 0.00)*
G04 Mirror:    No*
G04 Mode:      Positive*
G04 Rotation:  0*
G04 FullContactRelief:  No*
G04 UndefLineWidth:     6.00*
G04 ================== end FILE IDENTIFICATION RECORD ====================*
%FSLAX35Y35*MOIN*%
%IR0*IPPOS*OFA0.00000B0.00000*MIA0B0*SFA1.00000B1.00000*%
%ADD10C,.006*%
G75*
%LPD*%
G75*
G54D10*
G01X20103Y-86244D02*
G03I-4291J0D01*
G01X0Y-87362D02*
G03X15000Y-102362I15000J0D01*
G01X0Y-11811D02*
Y-87362D01*
G01X3937Y-7874D02*
G03X0Y-11811I0J-3937D01*
G01X15748Y-7874D02*
X3937D01*
G01X0Y7874D02*
G03X7874Y0I7874J0D01*
G01X818897D02*
X7874D01*
G01X0Y7874D02*
Y562992D01*
G01X7874Y570866D02*
G03X0Y562992I0J-7874D01*
G01X7874Y570866D02*
X326781D01*
G01X312004Y-102362D02*
X15000D01*
G01X46456Y0D02*
G03Y-7874I0J-3937D01*
G01X15748D02*
G03Y0I0J3937D01*
G01X287400Y-7874D02*
X46456D01*
G01X40452Y499724D02*
G03I-3051J0D01*
G01X41535Y535157D02*
G03I-4134J0D01*
G01X44685Y517441D02*
G03I-7284J0D01*
G01X121082Y39055D02*
G03I-5019J0D01*
G01X120807Y14567D02*
G03I-4744J0D01*
G01X319878Y-102362D02*
G03X312004I-3937J0D01*
G01X811771D02*
X319878D01*
G01X326770Y0D02*
G03Y-7874I0J-3937D01*
G01X287400D02*
G03Y0I0J3937D01*
G01X302165Y531496D02*
G03I-6890J0D01*
G01X597707Y-7874D02*
X326770D01*
G01X379921Y156220D02*
G03I-5906J0D01*
G01X342529Y530315D02*
G03X334655I-3937J0D01*
G01X342529Y520720D02*
G03X352474Y509057I11811J0D01*
G01X334655Y520720D02*
G03X351230Y501282I19685J0D01*
G01X384484Y503937D02*
X352475Y509057D01*
G01X383858Y496063D02*
X351231Y501282D01*
G01X442287Y503937D02*
X384484D01*
G01X442913Y496063D02*
X383858D01*
G01X342529Y530315D02*
Y520720D01*
G01X334655Y562992D02*
Y520720D01*
G01X346466Y570866D02*
G03X342529Y566929I0J-3937D01*
G01X334655Y555512D02*
G03X342529I3937J0D01*
G01X346466Y570866D02*
X480325D01*
G01X334655Y562992D02*
G03X326781Y570866I-7874J0D01*
G01X342529Y566929D02*
Y555512D01*
G01X415943Y539991D02*
G03I-4291J0D01*
G01X474316Y509060D02*
X442287Y503937D01*
G01X475560Y501285D02*
X442913Y496063D01*
G01X492136Y530315D02*
G03X484262I-3937J0D01*
G01X474316Y509060D02*
G03X484262Y520723I-1865J11663D01*
G01X475560Y501285D02*
G03X492136Y520723I-3109J19438D01*
G01X484262Y530315D02*
Y520723D01*
G01X492136Y562992D02*
Y520723D01*
G01X484262Y566929D02*
G03X480325Y570866I-3937J0D01*
G01X484262Y555512D02*
G03X492136I3937J0D01*
G01X500010Y570866D02*
G03X492136Y562992I0J-7874D01*
G01X500010Y570866D02*
X818897D01*
G01X484262Y566929D02*
Y555512D01*
G01X537401Y371299D02*
G03I-5905J0D01*
G01X538386Y531496D02*
G03I-6890J0D01*
G01X628416Y0D02*
G03Y-7874I0J-3937D01*
G01X597707D02*
G03Y0I0J3937D01*
G01X780315Y-7874D02*
X628416D01*
G01X602362Y116141D02*
G03I-5906J0D01*
G01X817003Y-86834D02*
G03I-4292J0D01*
G01X811771Y-102362D02*
G03X826771Y-87362I0J15000D01*
G01X811023Y0D02*
G03Y-7874I0J-3937D01*
G01X780315D02*
G03Y0I0J3937D01*
G01X822834Y-7874D02*
X811023D01*
G01X818897Y0D02*
G03X826771Y7874I0J7874D01*
G01X818897Y0D02*
X807086D01*
G01X787401Y198819D02*
G03I-5905J0D01*
G01X792421Y499724D02*
G03I-3051J0D01*
G01X793504Y535157D02*
G03I-4134J0D01*
G01X796653Y517441D02*
G03I-7283J0D01*
G01X826771Y562992D02*
G03X818897Y570866I-7874J0D01*
G01X826771Y-11811D02*
Y-87362D01*
G01Y-11811D02*
G03X822834Y-7874I-3937J0D01*
G01X826771Y562992D02*
Y7874D01*
M02*
